(kicad_pcb
	(version 20240108)
	(generator "pcbnew")
	(generator_version "8.0")
	(general
		(thickness 1.6)
		(legacy_teardrops no)
	)
	(paper "A4")
	(title_block
		(title "Jetson Orin Baseboard OCuLink Expansion")
		(date "2025-03-18")
		(rev "1.1.0")
		(company "Antmicro Ltd")
		(comment 1 "www.antmicro.com")
		(comment 9 "footprints 49-53 of 119")
	)
	(layers
		(0 "F.Cu" signal)
		(1 "In1.Cu" signal)
		(2 "In2.Cu" signal)
		(31 "B.Cu" signal)
		(32 "B.Adhes" user "B.Adhesive")
		(33 "F.Adhes" user "F.Adhesive")
		(34 "B.Paste" user)
		(35 "F.Paste" user)
		(36 "B.SilkS" user "B.Silkscreen")
		(37 "F.SilkS" user "F.Silkscreen")
		(38 "B.Mask" user)
		(39 "F.Mask" user)
		(40 "Dwgs.User" user "User.Drawings")
		(41 "Cmts.User" user "User.Comments")
		(42 "Eco1.User" user "User.Eco1")
		(43 "Eco2.User" user "User.Eco2")
		(44 "Edge.Cuts" user)
		(45 "Margin" user)
		(46 "B.CrtYd" user "B.Courtyard")
		(47 "F.CrtYd" user "F.Courtyard")
		(48 "B.Fab" user)
		(49 "F.Fab" user)
	)
	(footprint "antmicro-footprints:R_0402_1005Metric"
		(layer "F.Cu")
		(at 141.247 145.409 -90)
		(descr "Resistor SMD 0402")
		(tags "resistor SMD 0402")
		(property "Reference" "R2"
			(at 1.891 0.347 90)
			(layer "F.SilkS")
			(effects
				(font
					(size 0.7 0.7)
					(thickness 0.15)
				)
				(justify right top)
			)
		)
		(property "Value" "R_0R_0402"
			(at -1.011843 1.772047 90)
			(layer "F.Fab")
			(effects
				(font
					(size 0.7 0.7)
					(thickness 0.15)
				)
				(justify right top)
			)
		)
		(property "Footprint" "antmicro-footprints:R_0402_1005Metric"
			(at 0 0 90)
			(layer "F.Fab")
			(hide yes)
			(effects
				(font
					(size 1.27 1.27)
					(thickness 0.15)
				)
			)
		)
		(property "Datasheet" "https://industrial.panasonic.com/cdbs/www-data/pdf/RDA0000/AOA0000C301.pdf"
			(at 0 0 90)
			(layer "F.Fab")
			(hide yes)
			(effects
				(font
					(size 1.27 1.27)
					(thickness 0.15)
				)
			)
		)
		(property "Description" "SMD Chip Resistor, Jumper, 0 ohm, 100 mW, 0402 [1005 Metric], Thick Film, General Purpose"
			(at 0 0 90)
			(layer "F.Fab")
			(hide yes)
			(effects
				(font
					(size 1.27 1.27)
					(thickness 0.15)
				)
			)
		)
		(property "MPN" "ERJ2GE0R00X"
			(at 0 0 -90)
			(unlocked yes)
			(layer "F.Fab")
			(hide yes)
			(effects
				(font
					(size 1 1)
					(thickness 0.15)
				)
			)
		)
		(property "Manufacturer" "Panasonic"
			(at 0 0 -90)
			(unlocked yes)
			(layer "F.Fab")
			(hide yes)
			(effects
				(font
					(size 1 1)
					(thickness 0.15)
				)
			)
		)
		(property "License" "Apache-2.0"
			(at 0 0 -90)
			(unlocked yes)
			(layer "F.Fab")
			(hide yes)
			(effects
				(font
					(size 1 1)
					(thickness 0.15)
				)
			)
		)
		(property "Author" "Antmicro"
			(at 0 0 -90)
			(unlocked yes)
			(layer "F.Fab")
			(hide yes)
			(effects
				(font
					(size 1 1)
					(thickness 0.15)
				)
			)
		)
		(property "Val" "0R"
			(at 0 0 -90)
			(unlocked yes)
			(layer "F.Fab")
			(hide yes)
			(effects
				(font
					(size 1 1)
					(thickness 0.15)
				)
			)
		)
		(property "Tolerance" ""
			(at 0 0 -90)
			(unlocked yes)
			(layer "F.Fab")
			(hide yes)
			(effects
				(font
					(size 1 1)
					(thickness 0.15)
				)
			)
		)
		(property "Current" "1A"
			(at 0 0 -90)
			(unlocked yes)
			(layer "F.Fab")
			(hide yes)
			(effects
				(font
					(size 1 1)
					(thickness 0.15)
				)
			)
		)
		(sheetname "Root")
		(sheetfile "jetson-orin-baseboard-oculink-expansion.kicad_sch")
		(attr smd)
		(fp_rect
			(start -0.925 -0.47)
			(end 0.925 0.47)
			(stroke
				(width 0.05)
				(type default)
			)
			(fill none)
			(layer "F.CrtYd")
		)
		(fp_rect
			(start -0.5 -0.25)
			(end 0.5 0.25)
			(stroke
				(width 0.15)
				(type solid)
			)
			(fill none)
			(layer "F.Fab")
		)
		(fp_text user "${REFERENCE}"
			(at -0.95 3.168 90)
			(layer "F.Fab")
			(hide yes)
			(effects
				(font
					(size 0.7 0.7)
					(thickness 0.15)
				)
				(justify right top)
			)
		)
		(fp_text user "License: Apache-2.0"
			(at -0.95 5.169 90)
			(layer "F.Fab")
			(hide yes)
			(effects
				(font
					(size 0.7 0.7)
					(thickness 0.15)
				)
				(justify right top)
			)
		)
		(fp_text user "Author: Antmicro"
			(at -0.95 4.169 90)
			(layer "F.Fab")
			(hide yes)
			(effects
				(font
					(size 0.7 0.7)
					(thickness 0.15)
				)
				(justify right top)
			)
		)
		(pad "1" smd roundrect
			(at -0.48 0 270)
			(size 0.59 0.64)
			(layers "F.Cu" "F.Paste" "F.Mask")
			(roundrect_rratio 0.25)
			(net 69 "/~{PCIE_CWAKE}")
			(pintype "passive")
		)
		(pad "2" smd roundrect
			(at 0.48 0 270)
			(size 0.59 0.64)
			(layers "F.Cu" "F.Paste" "F.Mask")
			(roundrect_rratio 0.25)
			(net 54 "Net-(J1-~{CWAKE})")
			(pintype "passive")
		)
	)
	(footprint "antmicro-footprints:C_0402_1005Metric"
		(layer "F.Cu")
		(at 117.65 137.64 -90)
		(descr "Capacitor SMD 0402")
		(tags "capacitor SMD 0402")
		(property "Reference" "C13"
			(at 0.86 0.34 90)
			(layer "F.SilkS")
			(effects
				(font
					(size 0.7 0.7)
					(thickness 0.15)
				)
				(justify right top)
			)
		)
		(property "Value" "C_220n_0402"
			(at -1.022927 2.155213 90)
			(layer "F.Fab")
			(effects
				(font
					(size 0.7 0.7)
					(thickness 0.15)
				)
				(justify right top)
			)
		)
		(property "Footprint" "antmicro-footprints:C_0402_1005Metric"
			(at 0 0 90)
			(layer "F.Fab")
			(hide yes)
			(effects
				(font
					(size 1.27 1.27)
					(thickness 0.15)
				)
			)
		)
		(property "Datasheet" "https://www.yageo.com/en/Chart/Download/pdf/CC0402KRX5R6BB224"
			(at 0 0 90)
			(layer "F.Fab")
			(hide yes)
			(effects
				(font
					(size 1.27 1.27)
					(thickness 0.15)
				)
			)
		)
		(property "Description" "SMD Multilayer Ceramic Capacitor, 0.22 µF, 10 V, 0402 [1005 Metric], ± 10%, X5R, CC Series"
			(at 0 0 90)
			(layer "F.Fab")
			(hide yes)
			(effects
				(font
					(size 1.27 1.27)
					(thickness 0.15)
				)
			)
		)
		(property "MPN" "CC0402KRX5R6BB224"
			(at 0 0 -90)
			(unlocked yes)
			(layer "F.Fab")
			(hide yes)
			(effects
				(font
					(size 1 1)
					(thickness 0.15)
				)
			)
		)
		(property "Manufacturer" "YAGEO"
			(at 0 0 -90)
			(unlocked yes)
			(layer "F.Fab")
			(hide yes)
			(effects
				(font
					(size 1 1)
					(thickness 0.15)
				)
			)
		)
		(property "License" "Apache-2.0"
			(at 0 0 -90)
			(unlocked yes)
			(layer "F.Fab")
			(hide yes)
			(effects
				(font
					(size 1 1)
					(thickness 0.15)
				)
			)
		)
		(property "Author" "Antmicro"
			(at 0 0 -90)
			(unlocked yes)
			(layer "F.Fab")
			(hide yes)
			(effects
				(font
					(size 1 1)
					(thickness 0.15)
				)
			)
		)
		(property "Val" "220n"
			(at 0 0 -90)
			(unlocked yes)
			(layer "F.Fab")
			(hide yes)
			(effects
				(font
					(size 1 1)
					(thickness 0.15)
				)
			)
		)
		(property "Voltage" ""
			(at 0 0 -90)
			(unlocked yes)
			(layer "F.Fab")
			(hide yes)
			(effects
				(font
					(size 1 1)
					(thickness 0.15)
				)
			)
		)
		(property "Dielectric" ""
			(at 0 0 -90)
			(unlocked yes)
			(layer "F.Fab")
			(hide yes)
			(effects
				(font
					(size 1 1)
					(thickness 0.15)
				)
			)
		)
		(property "Public" "False"
			(at 0 0 -90)
			(unlocked yes)
			(layer "F.Fab")
			(hide yes)
			(effects
				(font
					(size 1 1)
					(thickness 0.15)
				)
			)
		)
		(sheetname "Root")
		(sheetfile "jetson-orin-baseboard-oculink-expansion.kicad_sch")
		(attr smd)
		(fp_rect
			(start -0.925 -0.47)
			(end 0.925 0.47)
			(stroke
				(width 0.05)
				(type default)
			)
			(fill none)
			(layer "F.CrtYd")
		)
		(fp_line
			(start -0.494 0.248)
			(end -0.494 -0.25)
			(stroke
				(width 0.15)
				(type solid)
			)
			(layer "F.Fab")
		)
		(fp_line
			(start 0.504 0.248)
			(end -0.494 0.248)
			(stroke
				(width 0.15)
				(type solid)
			)
			(layer "F.Fab")
		)
		(fp_line
			(start -0.494 -0.25)
			(end 0.504 -0.25)
			(stroke
				(width 0.15)
				(type solid)
			)
			(layer "F.Fab")
		)
		(fp_line
			(start 0.504 -0.25)
			(end 0.504 0.248)
			(stroke
				(width 0.15)
				(type solid)
			)
			(layer "F.Fab")
		)
		(fp_text user "${REFERENCE}"
			(at -0.939 4.599 90)
			(layer "F.Fab")
			(hide yes)
			(effects
				(font
					(size 0.7 0.7)
					(thickness 0.15)
				)
				(justify right top)
			)
		)
		(fp_text user "Author: Antmicro"
			(at -0.939 3.399 90)
			(layer "F.Fab")
			(hide yes)
			(effects
				(font
					(size 0.7 0.7)
					(thickness 0.15)
				)
				(justify right top)
			)
		)
		(fp_text user "License: Apache-2.0"
			(at -0.939 5.799 90)
			(layer "F.Fab")
			(hide yes)
			(effects
				(font
					(size 0.7 0.7)
					(thickness 0.15)
				)
				(justify right top)
			)
		)
		(pad "1" smd roundrect
			(at -0.48 0 270)
			(size 0.59 0.64)
			(layers "F.Cu" "F.Paste" "F.Mask")
			(roundrect_rratio 0.25)
			(net 57 "/PCIE_{O}_C.TX1+")
			(pintype "passive")
		)
		(pad "2" smd roundrect
			(at 0.48 0 270)
			(size 0.59 0.64)
			(layers "F.Cu" "F.Paste" "F.Mask")
			(roundrect_rratio 0.25)
			(net 58 "/PCIE_{O}_TX1+")
			(pintype "passive")
		)
	)
	(footprint "antmicro-footprints:R_0402_1005Metric"
		(layer "F.Cu")
		(at 120.79 136.96 -90)
		(descr "Resistor SMD 0402")
		(tags "resistor SMD 0402")
		(property "Reference" "R20"
			(at -1.13 -1.66 90)
			(layer "F.SilkS")
			(effects
				(font
					(size 0.7 0.7)
					(thickness 0.15)
				)
				(justify right top)
			)
		)
		(property "Value" "R_0R_0402"
			(at -1.011843 1.772047 90)
			(layer "F.Fab")
			(effects
				(font
					(size 0.7 0.7)
					(thickness 0.15)
				)
				(justify right top)
			)
		)
		(property "Footprint" "antmicro-footprints:R_0402_1005Metric"
			(at 0 0 90)
			(layer "F.Fab")
			(hide yes)
			(effects
				(font
					(size 1.27 1.27)
					(thickness 0.15)
				)
			)
		)
		(property "Datasheet" "https://industrial.panasonic.com/cdbs/www-data/pdf/RDA0000/AOA0000C301.pdf"
			(at 0 0 90)
			(layer "F.Fab")
			(hide yes)
			(effects
				(font
					(size 1.27 1.27)
					(thickness 0.15)
				)
			)
		)
		(property "Description" "SMD Chip Resistor, Jumper, 0 ohm, 100 mW, 0402 [1005 Metric], Thick Film, General Purpose"
			(at 0 0 90)
			(layer "F.Fab")
			(hide yes)
			(effects
				(font
					(size 1.27 1.27)
					(thickness 0.15)
				)
			)
		)
		(property "MPN" "ERJ2GE0R00X"
			(at 0 0 -90)
			(unlocked yes)
			(layer "F.Fab")
			(hide yes)
			(effects
				(font
					(size 1 1)
					(thickness 0.15)
				)
			)
		)
		(property "Manufacturer" "Panasonic"
			(at 0 0 -90)
			(unlocked yes)
			(layer "F.Fab")
			(hide yes)
			(effects
				(font
					(size 1 1)
					(thickness 0.15)
				)
			)
		)
		(property "License" "Apache-2.0"
			(at 0 0 -90)
			(unlocked yes)
			(layer "F.Fab")
			(hide yes)
			(effects
				(font
					(size 1 1)
					(thickness 0.15)
				)
			)
		)
		(property "Author" "Antmicro"
			(at 0 0 -90)
			(unlocked yes)
			(layer "F.Fab")
			(hide yes)
			(effects
				(font
					(size 1 1)
					(thickness 0.15)
				)
			)
		)
		(property "Val" "0R"
			(at 0 0 -90)
			(unlocked yes)
			(layer "F.Fab")
			(hide yes)
			(effects
				(font
					(size 1 1)
					(thickness 0.15)
				)
			)
		)
		(property "Tolerance" ""
			(at 0 0 -90)
			(unlocked yes)
			(layer "F.Fab")
			(hide yes)
			(effects
				(font
					(size 1 1)
					(thickness 0.15)
				)
			)
		)
		(property "Current" "1A"
			(at 0 0 -90)
			(unlocked yes)
			(layer "F.Fab")
			(hide yes)
			(effects
				(font
					(size 1 1)
					(thickness 0.15)
				)
			)
		)
		(sheetname "Root")
		(sheetfile "jetson-orin-baseboard-oculink-expansion.kicad_sch")
		(attr smd)
		(fp_rect
			(start -0.925 -0.47)
			(end 0.925 0.47)
			(stroke
				(width 0.05)
				(type default)
			)
			(fill none)
			(layer "F.CrtYd")
		)
		(fp_rect
			(start -0.5 -0.25)
			(end 0.5 0.25)
			(stroke
				(width 0.15)
				(type solid)
			)
			(fill none)
			(layer "F.Fab")
		)
		(fp_text user "License: Apache-2.0"
			(at -0.95 5.169 90)
			(layer "F.Fab")
			(hide yes)
			(effects
				(font
					(size 0.7 0.7)
					(thickness 0.15)
				)
				(justify right top)
			)
		)
		(fp_text user "Author: Antmicro"
			(at -0.95 4.169 90)
			(layer "F.Fab")
			(hide yes)
			(effects
				(font
					(size 0.7 0.7)
					(thickness 0.15)
				)
				(justify right top)
			)
		)
		(fp_text user "${REFERENCE}"
			(at -0.95 3.168 90)
			(layer "F.Fab")
			(hide yes)
			(effects
				(font
					(size 0.7 0.7)
					(thickness 0.15)
				)
				(justify right top)
			)
		)
		(pad "1" smd roundrect
			(at -0.48 0 270)
			(size 0.59 0.64)
			(layers "F.Cu" "F.Paste" "F.Mask")
			(roundrect_rratio 0.25)
			(net 64 "/I2C_SCL")
			(pintype "passive")
		)
		(pad "2" smd roundrect
			(at 0.48 0 270)
			(size 0.59 0.64)
			(layers "F.Cu" "F.Paste" "F.Mask")
			(roundrect_rratio 0.25)
			(net 126 "Net-(J1-SCL)")
			(pintype "passive")
		)
	)
	(footprint "antmicro-footprints:TP_SMD_0.75mm"
		(layer "F.Cu")
		(at 114.6 127.508)
		(property "Reference" "TP4"
			(at -1.05 1.432 0)
			(layer "F.SilkS")
			(effects
				(font
					(size 0.7 0.7)
					(thickness 0.15)
				)
				(justify left bottom)
			)
		)
		(property "Value" "TP_0.75mm_SMD"
			(at 0 1.2 0)
			(layer "F.Fab")
			(effects
				(font
					(size 0.7 0.7)
					(thickness 0.15)
				)
				(justify left bottom)
			)
		)
		(property "Footprint" "antmicro-footprints:TP_SMD_0.75mm"
			(at 0 0 0)
			(layer "F.Fab")
			(hide yes)
			(effects
				(font
					(size 1.27 1.27)
					(thickness 0.15)
				)
			)
		)
		(property "Description" "SMT test point"
			(at 0 0 0)
			(layer "F.Fab")
			(hide yes)
			(effects
				(font
					(size 1.27 1.27)
					(thickness 0.15)
				)
			)
		)
		(property "MPN" ""
			(at 0 0 0)
			(unlocked yes)
			(layer "F.Fab")
			(hide yes)
			(effects
				(font
					(size 1 1)
					(thickness 0.15)
				)
			)
		)
		(property "Manufacturer" ""
			(at 0 0 0)
			(unlocked yes)
			(layer "F.Fab")
			(hide yes)
			(effects
				(font
					(size 1 1)
					(thickness 0.15)
				)
			)
		)
		(property "Author" "Antmicro"
			(at 0 0 0)
			(unlocked yes)
			(layer "F.Fab")
			(hide yes)
			(effects
				(font
					(size 1 1)
					(thickness 0.15)
				)
			)
		)
		(property "License" "Apache-2.0"
			(at 0 0 0)
			(unlocked yes)
			(layer "F.Fab")
			(hide yes)
			(effects
				(font
					(size 1 1)
					(thickness 0.15)
				)
			)
		)
		(property "Public" "False"
			(at 0 0 0)
			(unlocked yes)
			(layer "F.Fab")
			(hide yes)
			(effects
				(font
					(size 1 1)
					(thickness 0.15)
				)
			)
		)
		(sheetname "Root")
		(sheetfile "jetson-orin-baseboard-oculink-expansion.kicad_sch")
		(attr exclude_from_pos_files exclude_from_bom)
		(fp_circle
			(center 0 0)
			(end 0.475 0)
			(stroke
				(width 0.05)
				(type default)
			)
			(fill none)
			(layer "F.CrtYd")
		)
		(fp_text user "Author: Antmicro"
			(at -0.4 3.901 0)
			(layer "F.Fab")
			(hide yes)
			(effects
				(font
					(size 0.7 0.7)
					(thickness 0.15)
				)
				(justify left bottom)
			)
		)
		(fp_text user "${REFERENCE}"
			(at -0.4 2.7 0)
			(layer "F.Fab")
			(hide yes)
			(effects
				(font
					(size 0.7 0.7)
					(thickness 0.15)
				)
				(justify left bottom)
			)
		)
		(fp_text user "License: Apache-2.0"
			(at -0.4 5.101 0)
			(layer "F.Fab")
			(hide yes)
			(effects
				(font
					(size 0.7 0.7)
					(thickness 0.15)
				)
				(justify left bottom)
			)
		)
		(pad "1" smd circle
			(at 0 0)
			(size 0.75 0.75)
			(layers "F.Cu" "F.Mask")
			(net 108 "Net-(U3-SCL)")
			(pinfunction "1")
			(pintype "passive")
		)
	)
	(footprint "antmicro-footprints:C_0402_1005Metric"
		(layer "F.Cu")
		(at 116.41875 137.65 -90)
		(descr "Capacitor SMD 0402")
		(tags "capacitor SMD 0402")
		(property "Reference" "C14"
			(at 0.85 0.32875 90)
			(layer "F.SilkS")
			(effects
				(font
					(size 0.7 0.7)
					(thickness 0.15)
				)
				(justify right top)
			)
		)
		(property "Value" "C_220n_0402"
			(at -1.022927 2.155213 90)
			(layer "F.Fab")
			(effects
				(font
					(size 0.7 0.7)
					(thickness 0.15)
				)
				(justify right top)
			)
		)
		(property "Footprint" "antmicro-footprints:C_0402_1005Metric"
			(at 0 0 90)
			(layer "F.Fab")
			(hide yes)
			(effects
				(font
					(size 1.27 1.27)
					(thickness 0.15)
				)
			)
		)
		(property "Datasheet" "https://www.yageo.com/en/Chart/Download/pdf/CC0402KRX5R6BB224"
			(at 0 0 90)
			(layer "F.Fab")
			(hide yes)
			(effects
				(font
					(size 1.27 1.27)
					(thickness 0.15)
				)
			)
		)
		(property "Description" "SMD Multilayer Ceramic Capacitor, 0.22 µF, 10 V, 0402 [1005 Metric], ± 10%, X5R, CC Series"
			(at 0 0 90)
			(layer "F.Fab")
			(hide yes)
			(effects
				(font
					(size 1.27 1.27)
					(thickness 0.15)
				)
			)
		)
		(property "MPN" "CC0402KRX5R6BB224"
			(at 0 0 -90)
			(unlocked yes)
			(layer "F.Fab")
			(hide yes)
			(effects
				(font
					(size 1 1)
					(thickness 0.15)
				)
			)
		)
		(property "Manufacturer" "YAGEO"
			(at 0 0 -90)
			(unlocked yes)
			(layer "F.Fab")
			(hide yes)
			(effects
				(font
					(size 1 1)
					(thickness 0.15)
				)
			)
		)
		(property "License" "Apache-2.0"
			(at 0 0 -90)
			(unlocked yes)
			(layer "F.Fab")
			(hide yes)
			(effects
				(font
					(size 1 1)
					(thickness 0.15)
				)
			)
		)
		(property "Author" "Antmicro"
			(at 0 0 -90)
			(unlocked yes)
			(layer "F.Fab")
			(hide yes)
			(effects
				(font
					(size 1 1)
					(thickness 0.15)
				)
			)
		)
		(property "Val" "220n"
			(at 0 0 -90)
			(unlocked yes)
			(layer "F.Fab")
			(hide yes)
			(effects
				(font
					(size 1 1)
					(thickness 0.15)
				)
			)
		)
		(property "Voltage" ""
			(at 0 0 -90)
			(unlocked yes)
			(layer "F.Fab")
			(hide yes)
			(effects
				(font
					(size 1 1)
					(thickness 0.15)
				)
			)
		)
		(property "Dielectric" ""
			(at 0 0 -90)
			(unlocked yes)
			(layer "F.Fab")
			(hide yes)
			(effects
				(font
					(size 1 1)
					(thickness 0.15)
				)
			)
		)
		(property "Public" "False"
			(at 0 0 -90)
			(unlocked yes)
			(layer "F.Fab")
			(hide yes)
			(effects
				(font
					(size 1 1)
					(thickness 0.15)
				)
			)
		)
		(sheetname "Root")
		(sheetfile "jetson-orin-baseboard-oculink-expansion.kicad_sch")
		(attr smd)
		(fp_rect
			(start -0.925 -0.47)
			(end 0.925 0.47)
			(stroke
				(width 0.05)
				(type default)
			)
			(fill none)
			(layer "F.CrtYd")
		)
		(fp_line
			(start -0.494 0.248)
			(end -0.494 -0.25)
			(stroke
				(width 0.15)
				(type solid)
			)
			(layer "F.Fab")
		)
		(fp_line
			(start 0.504 0.248)
			(end -0.494 0.248)
			(stroke
				(width 0.15)
				(type solid)
			)
			(layer "F.Fab")
		)
		(fp_line
			(start -0.494 -0.25)
			(end 0.504 -0.25)
			(stroke
				(width 0.15)
				(type solid)
			)
			(layer "F.Fab")
		)
		(fp_line
			(start 0.504 -0.25)
			(end 0.504 0.248)
			(stroke
				(width 0.15)
				(type solid)
			)
			(layer "F.Fab")
		)
		(fp_text user "License: Apache-2.0"
			(at -0.939 5.799 90)
			(layer "F.Fab")
			(hide yes)
			(effects
				(font
					(size 0.7 0.7)
					(thickness 0.15)
				)
				(justify right top)
			)
		)
		(fp_text user "Author: Antmicro"
			(at -0.939 3.399 90)
			(layer "F.Fab")
			(hide yes)
			(effects
				(font
					(size 0.7 0.7)
					(thickness 0.15)
				)
				(justify right top)
			)
		)
		(fp_text user "${REFERENCE}"
			(at -0.939 4.599 90)
			(layer "F.Fab")
			(hide yes)
			(effects
				(font
					(size 0.7 0.7)
					(thickness 0.15)
				)
				(justify right top)
			)
		)
		(pad "1" smd roundrect
			(at -0.48 0 270)
			(size 0.59 0.64)
			(layers "F.Cu" "F.Paste" "F.Mask")
			(roundrect_rratio 0.25)
			(net 31 "/PCIE_{O}_C.TX0-")
			(pintype "passive")
		)
		(pad "2" smd roundrect
			(at 0.48 0 270)
			(size 0.59 0.64)
			(layers "F.Cu" "F.Paste" "F.Mask")
			(roundrect_rratio 0.25)
			(net 56 "/PCIE_{O}_TX0-")
			(pintype "passive")
		)
	)
)
